# S9S_MB_2U (Grand Teton) — schematic netlist excerpt (pin names and nets, part order shuffled) for the footprints in the layout excerpt that follows; sources: Cadence DE-HDL packaged netlist, KiCad conversion of 03242023_DA0F0TMBIJ0_F0T_Motherboard_J_brd_V01_OCP.brd

Q123  MOSFET_NCH_DUAL  PJT138K EMPTY  pkg SOT363XD  page 156
  S1  = GND
  G1  = P12V_OCP_EN_1_R
  D2  = P12V_OCP_UV_1_R
  S2  = GND
  G2  = P12V_OCP_1_EN_G
  D1  = P12V_OCP_1_EN_G

JP10  CONN3_210HP1030BR1  CONN3_210-HP1-030BR1 IO  pkg HEADER1X3XG  page 305
  \1\  = SMB_SML1_PMBUS_HSC_MODULE_SCL
  \2\  = SMB_SML1_PMBUS_HSC_MODULE_SDA
  \3\  = GND

(kicad_pcb
	(version 20260206)
	(generator "pcbnew")
	(generator_version "10.0")
	(general
		(thickness 1.6)
		(legacy_teardrops no)
	)
	(paper "A4")
	(title_block
		(title "03242023_DA0F0TMBIJ0_F0T_Motherboard_J_brd_V01_OCP.brd")
		(comment 1 "Grand Teton / footprints 540-541 of 6105")
	)
	(layers
		(0 "F.Cu" signal "TOP")
		(4 "In1.Cu" signal "GND")
		(6 "In2.Cu" signal "IN1")
		(8 "In3.Cu" signal "GND1")
		(10 "In4.Cu" signal "IN2")
		(12 "In5.Cu" signal "GND2")
		(14 "In6.Cu" signal "IN3")
		(16 "In7.Cu" signal "GND3")
		(18 "In8.Cu" signal "VCC")
		(20 "In9.Cu" signal "VCC1")
		(22 "In10.Cu" signal "GND4")
		(24 "In11.Cu" signal "IN4")
		(26 "In12.Cu" signal "GND5")
		(28 "In13.Cu" signal "IN5")
		(30 "In14.Cu" signal "GND6")
		(32 "In15.Cu" signal "IN6")
		(34 "In16.Cu" signal "GND7")
		(2 "B.Cu" signal "BOTTOM")
		(9 "F.Adhes" user "F.Adhesive")
		(11 "B.Adhes" user "B.Adhesive")
		(13 "F.Paste" user "Package Geometry/Pastemask Top")
		(15 "B.Paste" user "Package Geometry/Pastemask Bottom")
		(5 "F.SilkS" user "Ref Des/Silkscreen Top")
		(7 "B.SilkS" user "Ref Des/Silkscreen Bottom")
		(1 "F.Mask" user "Board Geometry/Soldermask Top")
		(3 "B.Mask" user "Board Geometry/Soldermask Bottom")
		(17 "Dwgs.User" user "User.Drawings")
		(19 "Cmts.User" user "User.Comments")
		(21 "Eco1.User" user "User.Eco1")
		(23 "Eco2.User" user "User.Eco2")
		(25 "Edge.Cuts" user "Board Geometry/Outline")
		(27 "Margin" user)
		(31 "F.CrtYd" user "Package Geometry/Place Bound Top")
		(29 "B.CrtYd" user "Package Geometry/Place Bound Bottom")
		(35 "F.Fab" user "Ref Des/Assembly Top")
		(33 "B.Fab" user "Ref Des/Assembly Bottom")
	)
	(footprint ""
		(layer "F.Cu")
		(at 466.094318 -39.106094)
		(property "Reference" "Q123"
			(at -1.32334 -2.675128 0)
			(unlocked yes)
			(layer "F.SilkS")
			(effects
				(font
					(size 0.7874 0.5842)
					(thickness 0.1524)
				)
				(justify left)
			)
		)
		(property "Value" ""
			(at 0 0 0)
			(layer "F.Fab")
			(effects
				(font
					(size 1.27 1.27)
				)
			)
		)
		(duplicate_pad_numbers_are_jumpers no)
		(fp_line
			(start -1.332738 -1.100074)
			(end -0.4826 -1.100074)
			(stroke
				(width 0.1524)
				(type default)
			)
			(layer "F.SilkS")
		)
		(fp_line
			(start -1.332738 1.100074)
			(end -1.332738 -1.100074)
			(stroke
				(width 0.1524)
				(type default)
			)
			(layer "F.SilkS")
		)
		(fp_line
			(start -0.4826 -1.100074)
			(end 0 -0.541274)
			(stroke
				(width 0.1524)
				(type default)
			)
			(layer "F.SilkS")
		)
		(fp_line
			(start 0 -0.541274)
			(end 0.4826 -1.100074)
			(stroke
				(width 0.1524)
				(type default)
			)
			(layer "F.SilkS")
		)
		(fp_line
			(start 0.4826 -1.100074)
			(end 1.332738 -1.100074)
			(stroke
				(width 0.1524)
				(type default)
			)
			(layer "F.SilkS")
		)
		(fp_line
			(start 1.332738 -1.100074)
			(end 1.332738 1.100074)
			(stroke
				(width 0.1524)
				(type default)
			)
			(layer "F.SilkS")
		)
		(fp_line
			(start 1.332738 1.100074)
			(end -1.332738 1.100074)
			(stroke
				(width 0.1524)
				(type default)
			)
			(layer "F.SilkS")
		)
		(fp_poly
			(pts
				(xy -0.672338 -2.038096) (xy -1.023366 -1.33604) (xy -1.374394 -2.038096)
			)
			(stroke
				(width 0)
				(type default)
			)
			(fill yes)
			(layer "F.SilkS")
		)
		(fp_line
			(start -0.674878 -1.100074)
			(end 0.674878 -1.100074)
			(stroke
				(width 0.1)
				(type default)
			)
			(layer "F.Fab")
		)
		(fp_line
			(start -0.674878 1.100074)
			(end -0.674878 -1.100074)
			(stroke
				(width 0.1)
				(type default)
			)
			(layer "F.Fab")
		)
		(fp_line
			(start 0.674878 -1.100074)
			(end 0.674878 1.100074)
			(stroke
				(width 0.1)
				(type default)
			)
			(layer "F.Fab")
		)
		(fp_line
			(start 0.674878 1.100074)
			(end -0.674878 1.100074)
			(stroke
				(width 0.1)
				(type default)
			)
			(layer "F.Fab")
		)
		(fp_poly
			(pts
				(xy -2.2352 -0.298958) (xy -2.2352 -1.001014) (xy -1.533144 -0.649986)
			)
			(stroke
				(width 0)
				(type default)
			)
			(fill yes)
			(layer "F.Fab")
		)
		(pad "1" smd rect
			(at -0.94996 -0.649986 90)
			(size 0.4318 0.508)
			(layers "F.Cu" "F.Mask" "F.Paste")
			(net "GND")
		)
		(pad "2" smd rect
			(at -0.94996 0 90)
			(size 0.4318 0.508)
			(layers "F.Cu" "F.Mask" "F.Paste")
			(net "P12V_OCP_EN_1_R")
		)
		(pad "3" smd rect
			(at -0.94996 0.649986 90)
			(size 0.4318 0.508)
			(layers "F.Cu" "F.Mask" "F.Paste")
			(net "P12V_OCP_UV_1_R")
		)
		(pad "4" smd rect
			(at 0.94996 0.649986 90)
			(size 0.4318 0.508)
			(layers "F.Cu" "F.Mask" "F.Paste")
			(net "GND")
		)
		(pad "5" smd rect
			(at 0.94996 0 90)
			(size 0.4318 0.508)
			(layers "F.Cu" "F.Mask" "F.Paste")
			(net "P12V_OCP_1_EN_G")
		)
		(pad "6" smd rect
			(at 0.94996 -0.649986 90)
			(size 0.4318 0.508)
			(layers "F.Cu" "F.Mask" "F.Paste")
			(net "P12V_OCP_1_EN_G")
		)
	)
	(footprint ""
		(layer "F.Cu")
		(at 279.39238 -437.53278)
		(property "Reference" "JP10"
			(at -1.4097 -2.009648 0)
			(unlocked yes)
			(layer "F.SilkS")
			(effects
				(font
					(size 0.7874 0.5842)
					(thickness 0.1524)
				)
				(justify left)
			)
		)
		(property "Value" ""
			(at 0 0 0)
			(layer "F.Fab")
			(effects
				(font
					(size 1.27 1.27)
				)
			)
		)
		(duplicate_pad_numbers_are_jumpers no)
		(fp_line
			(start -1.249934 -1.320038)
			(end 1.249934 -1.320038)
			(stroke
				(width 0.1524)
				(type default)
			)
			(layer "F.SilkS")
		)
		(fp_line
			(start -1.249934 6.400038)
			(end -1.249934 -1.320038)
			(stroke
				(width 0.1524)
				(type default)
			)
			(layer "F.SilkS")
		)
		(fp_line
			(start 1.249934 -1.320038)
			(end 1.249934 6.400038)
			(stroke
				(width 0.1524)
				(type default)
			)
			(layer "F.SilkS")
		)
		(fp_line
			(start 1.249934 6.400038)
			(end -1.249934 6.400038)
			(stroke
				(width 0.1524)
				(type default)
			)
			(layer "F.SilkS")
		)
		(fp_poly
			(pts
				(xy -2.5654 -0.556514) (xy -1.452372 0) (xy -2.5654 0.556514)
			)
			(stroke
				(width 0)
				(type default)
			)
			(fill yes)
			(layer "F.SilkS")
		)
		(fp_line
			(start -1.249934 -1.320038)
			(end 1.249934 -1.320038)
			(stroke
				(width 0.1)
				(type default)
			)
			(layer "F.Fab")
		)
		(fp_line
			(start -1.249934 6.400038)
			(end -1.249934 -1.320038)
			(stroke
				(width 0.1)
				(type default)
			)
			(layer "F.Fab")
		)
		(fp_line
			(start 1.249934 -1.320038)
			(end 1.249934 6.400038)
			(stroke
				(width 0.1)
				(type default)
			)
			(layer "F.Fab")
		)
		(fp_line
			(start 1.249934 6.400038)
			(end -1.249934 6.400038)
			(stroke
				(width 0.1)
				(type default)
			)
			(layer "F.Fab")
		)
		(fp_poly
			(pts
				(xy -2.5654 -0.556514) (xy -1.452372 0) (xy -2.5654 0.556514)
			)
			(stroke
				(width 0)
				(type default)
			)
			(fill yes)
			(layer "F.Fab")
		)
		(fp_text user "3"
			(at -1.778 5.13207 0)
			(unlocked yes)
			(layer "F.SilkS")
			(effects
				(font
					(size 0.7874 0.5842)
					(thickness 0.1524)
				)
			)
		)
		(fp_text user "3"
			(at -1.1557 5.18287 0)
			(unlocked yes)
			(layer "B.SilkS")
			(effects
				(font
					(size 0.7874 0.5842)
					(thickness 0.1524)
				)
				(justify mirror)
			)
		)
		(fp_text user "1"
			(at -1.143 0.02667 0)
			(unlocked yes)
			(layer "B.SilkS")
			(effects
				(font
					(size 0.7874 0.5842)
					(thickness 0.1524)
				)
				(justify mirror)
			)
		)
		(fp_text user "3"
			(at -1.1557 5.18287 0)
			(unlocked yes)
			(layer "B.Fab")
			(effects
				(font
					(size 0.7874 0.5842)
					(thickness 0.1524)
				)
				(justify mirror)
			)
		)
		(fp_text user "1"
			(at -1.143 0.02667 0)
			(unlocked yes)
			(layer "B.Fab")
			(effects
				(font
					(size 0.7874 0.5842)
					(thickness 0.1524)
				)
				(justify mirror)
			)
		)
		(fp_text user "3"
			(at -1.778 5.13207 0)
			(unlocked yes)
			(layer "F.Fab")
			(effects
				(font
					(size 0.7874 0.5842)
					(thickness 0.1524)
				)
			)
		)
		(pad "1" thru_hole rect
			(at 0 0)
			(size 1.5494 1.5494)
			(drill 1.0414)
			(layers "*.Cu" "*.Mask")
			(remove_unused_layers no)
			(net "SMB_SML1_PMBUS_HSC_MODULE_SCL")
			(clearance 0)
			(padstack
				(mode front_inner_back)
				(layer "Inner"
					(shape circle)
					(size 1.5494 1.5494)
					(clearance 0)
				)
				(layer "B.Cu"
					(shape rect)
					(size 1.5494 1.5494)
					(clearance 0)
				)
			)
		)
		(pad "2" thru_hole circle
			(at 0 2.54)
			(size 1.5494 1.5494)
			(drill 1.0414)
			(layers "*.Cu" "*.Mask")
			(remove_unused_layers no)
			(net "SMB_SML1_PMBUS_HSC_MODULE_SDA")
			(clearance 0)
		)
		(pad "3" thru_hole circle
			(at 0 5.08)
			(size 1.5494 1.5494)
			(drill 1.0414)
			(layers "*.Cu" "*.Mask")
			(remove_unused_layers no)
			(net "GND")
			(clearance 0)
		)
	)
)
